FILE_TYPE = CONNECTIVITY;
{Allegro Design Entry HDL 17.4-2019 S026 (4007227) 1/17/2022}
"PAGE_NUMBER" = 166;
0"NC";
END.
